(kicad_pcb
	(version 20260206)
	(generator "pcbnew")
	(generator_version "10.0")
	(general
		(thickness 1.6)
		(legacy_teardrops no)
	)
	(paper "A4")
	(title_block
		(title "Wiwynn_Tioga_Pass_MB.brd")
		(comment 1 "Tioga Pass / footprints 918-925 of 4770")
	)
	(layers
		(0 "F.Cu" signal "TOP")
		(4 "In1.Cu" signal "L2GND")
		(6 "In2.Cu" signal "L3")
		(8 "In3.Cu" signal "L4GND")
		(10 "In4.Cu" signal "L5")
		(12 "In5.Cu" signal "L6GND")
		(14 "In6.Cu" signal "L7VCC")
		(16 "In7.Cu" signal "L8VCC")
		(18 "In8.Cu" signal "L9GND")
		(20 "In9.Cu" signal "L10")
		(22 "In10.Cu" signal "L11GND")
		(24 "In11.Cu" signal "L12")
		(26 "In12.Cu" signal "L13GND")
		(2 "B.Cu" signal "BOTTOM")
		(9 "F.Adhes" user "F.Adhesive")
		(11 "B.Adhes" user "B.Adhesive")
		(13 "F.Paste" user "Package Geometry/Pastemask Top")
		(15 "B.Paste" user "Package Geometry/Pastemask Bottom")
		(5 "F.SilkS" user "Ref Des/Silkscreen Top")
		(7 "B.SilkS" user "Ref Des/Silkscreen Bottom")
		(1 "F.Mask" user "Board Geometry/Soldermask Top")
		(3 "B.Mask" user "Board Geometry/Soldermask Bottom")
		(17 "Dwgs.User" user "User.Drawings")
		(19 "Cmts.User" user "User.Comments")
		(21 "Eco1.User" user "User.Eco1")
		(23 "Eco2.User" user "User.Eco2")
		(25 "Edge.Cuts" user "Board Geometry/Outline")
		(27 "Margin" user)
		(31 "F.CrtYd" user "Package Geometry/Place Bound Top")
		(29 "B.CrtYd" user "Package Geometry/Place Bound Bottom")
		(35 "F.Fab" user "Ref Des/Assembly Top")
		(33 "B.Fab" user "Ref Des/Assembly Bottom")
	)
	(footprint ""
		(layer "F.Cu")
		(at 372.550182 -149.543262 180)
		(property "Reference" "RT43"
			(at 0 0 180)
			(layer "F.SilkS")
			(hide yes)
			(effects
				(font
					(size 1.27 1.27)
				)
			)
		)
		(property "Value" "*"
			(at -0.0254 -2.6289 180)
			(unlocked yes)
			(layer "F.Fab")
			(hide yes)
			(effects
				(font
					(size 1.27 1.016)
					(thickness 0.1524)
				)
			)
		)
		(property "Device Type" "1R3F-GP_RCL_GP-1R3F-GP,64.1R00A"
			(at -0.0254 -4.1529 180)
			(unlocked yes)
			(layer "F.Fab")
			(hide yes)
			(effects
				(font
					(size 1.27 1.016)
					(thickness 0.1524)
				)
			)
		)
		(duplicate_pad_numbers_are_jumpers no)
		(fp_line
			(start 0.2032 0)
			(end 0.4826 0)
			(stroke
				(width 0.2032)
				(type default)
			)
			(layer "F.SilkS")
		)
		(fp_line
			(start -0.4826 0)
			(end -0.2032 0)
			(stroke
				(width 0.2032)
				(type default)
			)
			(layer "F.SilkS")
		)
		(fp_rect
			(start -0.5842 1.3335)
			(end 0.5842 -1.3335)
			(stroke
				(width 0)
				(type default)
			)
			(fill no)
			(layer "F.CrtYd")
		)
		(fp_rect
			(start -0.5842 1.3335)
			(end 0.5842 -1.3335)
			(stroke
				(width 0)
				(type default)
			)
			(fill no)
			(layer "F.Fab")
		)
		(pad "1" smd custom
			(at 0 -0.762 180)
			(size 0.2159 0.2159)
			(layers "F.Cu" "F.Mask" "F.Paste")
			(net "VR_PVNN_PCH_PH1_PHASE_SW_RC")
			(options
				(clearance outline)
				(anchor circle)
			)
			(primitives
				(gr_poly
					(pts
						(arc
							(start -0.3302 -0.4318)
							(mid -0.402042 -0.402042)
							(end -0.4318 -0.3302)
						)
						(arc
							(start -0.4318 0.3302)
							(mid -0.402042 0.402042)
							(end -0.3302 0.4318)
						)
						(arc
							(start 0.3302 0.4318)
							(mid 0.402042 0.402042)
							(end 0.4318 0.3302)
						)
						(arc
							(start 0.4318 -0.3302)
							(mid 0.402042 -0.402042)
							(end 0.3302 -0.4318)
						)
					)
					(width 0)
					(fill yes)
				)
			)
		)
		(pad "2" smd custom
			(at 0 0.762 180)
			(size 0.2159 0.2159)
			(layers "F.Cu" "F.Mask" "F.Paste")
			(net "GND")
			(options
				(clearance outline)
				(anchor circle)
			)
			(primitives
				(gr_poly
					(pts
						(arc
							(start -0.3302 -0.4318)
							(mid -0.402042 -0.402042)
							(end -0.4318 -0.3302)
						)
						(arc
							(start -0.4318 0.3302)
							(mid -0.402042 0.402042)
							(end -0.3302 0.4318)
						)
						(arc
							(start 0.3302 0.4318)
							(mid 0.402042 0.402042)
							(end 0.4318 0.3302)
						)
						(arc
							(start 0.4318 -0.3302)
							(mid 0.402042 -0.402042)
							(end 0.3302 -0.4318)
						)
					)
					(width 0)
					(fill yes)
				)
			)
		)
	)
	(footprint ""
		(layer "F.Cu")
		(at 402.590254 -40.985948 90)
		(property "Reference" "R1T37"
			(at 0 0 90)
			(layer "F.SilkS")
			(hide yes)
			(effects
				(font
					(size 1.27 1.27)
				)
			)
		)
		(property "Value" ""
			(at 0 0 90)
			(layer "F.Fab")
			(effects
				(font
					(size 1.27 1.27)
				)
			)
		)
		(duplicate_pad_numbers_are_jumpers no)
		(fp_poly
			(pts
				(xy -0.2794 -0.1016) (xy 0.2794 -0.1016) (xy 0.2794 0.9906) (xy -0.2794 0.9906)
			)
			(stroke
				(width 0)
				(type default)
			)
			(fill no)
			(layer "F.CrtYd")
		)
		(fp_line
			(start 0.2794 -0.1016)
			(end -0.2794 -0.1016)
			(stroke
				(width 0.1)
				(type default)
			)
			(layer "F.Fab")
		)
		(fp_line
			(start -0.2794 -0.1016)
			(end -0.2794 0.9906)
			(stroke
				(width 0.1)
				(type default)
			)
			(layer "F.Fab")
		)
		(fp_line
			(start 0.2794 0.9906)
			(end 0.2794 -0.1016)
			(stroke
				(width 0.1)
				(type default)
			)
			(layer "F.Fab")
		)
		(fp_line
			(start -0.2794 0.9906)
			(end 0.2794 0.9906)
			(stroke
				(width 0.1)
				(type default)
			)
			(layer "F.Fab")
		)
		(pad "1" smd rect
			(at 0 0 90)
			(size 0.508 0.508)
			(layers "F.Cu" "F.Mask" "F.Paste")
			(net "FM_CPU1_PROCHOT_LVT3_N")
		)
		(pad "2" smd rect
			(at 0 0.889 90)
			(size 0.508 0.508)
			(layers "F.Cu" "F.Mask" "F.Paste")
			(net "FM_CPU1_PROCHOT_LVT3_BMC_N")
		)
		(zone
			(layer "F.Cu")
			(hatch none 0.5)
			(connect_pads
				(clearance 0)
			)
			(min_thickness 0.25)
			(keepout
				(tracks allowed)
				(vias not_allowed)
				(pads allowed)
				(copperpour not_allowed)
				(footprints allowed)
			)
			(placement
				(enabled no)
				(sheetname "")
			)
			(fill
				(thermal_gap 0.5)
				(thermal_bridge_width 0.5)
				(island_removal_mode 0)
			)
			(polygon
				(pts
					(xy 402.844254 -40.731948) (xy 402.844254 -41.239948) (xy 403.225254 -41.239948) (xy 403.225254 -40.731948)
				)
			)
		)
		(zone
			(layer "F.Cu")
			(hatch none 0.5)
			(connect_pads
				(clearance 0)
			)
			(min_thickness 0.25)
			(keepout
				(tracks not_allowed)
				(vias allowed)
				(pads allowed)
				(copperpour not_allowed)
				(footprints allowed)
			)
			(placement
				(enabled no)
				(sheetname "")
			)
			(fill
				(thermal_gap 0.5)
				(thermal_bridge_width 0.5)
				(island_removal_mode 0)
			)
			(polygon
				(pts
					(xy 403.225254 -40.731948) (xy 403.225254 -41.239948) (xy 402.844254 -41.239948) (xy 402.844254 -40.731948)
				)
			)
		)
	)
	(footprint ""
		(layer "F.Cu")
		(at 18.071592 -117.145054 90)
		(property "Reference" "R1B21"
			(at 0 0 90)
			(layer "F.SilkS")
			(hide yes)
			(effects
				(font
					(size 1.27 1.27)
				)
			)
		)
		(property "Value" ""
			(at 0 0 90)
			(layer "F.Fab")
			(effects
				(font
					(size 1.27 1.27)
				)
			)
		)
		(duplicate_pad_numbers_are_jumpers no)
		(fp_rect
			(start -0.2794 0.9906)
			(end 0.2794 -0.1016)
			(stroke
				(width 0)
				(type default)
			)
			(fill no)
			(layer "F.CrtYd")
		)
		(fp_line
			(start 0.2794 -0.1016)
			(end -0.2794 -0.1016)
			(stroke
				(width 0.1)
				(type default)
			)
			(layer "F.Fab")
		)
		(fp_line
			(start -0.2794 -0.1016)
			(end -0.2794 0.9906)
			(stroke
				(width 0.1)
				(type default)
			)
			(layer "F.Fab")
		)
		(fp_line
			(start 0.2794 0.9906)
			(end 0.2794 -0.1016)
			(stroke
				(width 0.1)
				(type default)
			)
			(layer "F.Fab")
		)
		(fp_line
			(start -0.2794 0.9906)
			(end 0.2794 0.9906)
			(stroke
				(width 0.1)
				(type default)
			)
			(layer "F.Fab")
		)
		(pad "1" smd rect
			(at 0 0 90)
			(size 0.508 0.508)
			(layers "F.Cu" "F.Mask" "F.Paste")
			(net "P3V3_STBY")
		)
		(pad "2" smd rect
			(at 0 0.889 90)
			(size 0.508 0.508)
			(layers "F.Cu" "F.Mask" "F.Paste")
			(net "FAN_TACH2")
		)
		(zone
			(layer "F.Cu")
			(hatch none 0.5)
			(connect_pads
				(clearance 0)
			)
			(min_thickness 0.25)
			(keepout
				(tracks allowed)
				(vias not_allowed)
				(pads allowed)
				(copperpour not_allowed)
				(footprints allowed)
			)
			(placement
				(enabled no)
				(sheetname "")
			)
			(fill
				(thermal_gap 0.5)
				(thermal_bridge_width 0.5)
				(island_removal_mode 0)
			)
			(polygon
				(pts
					(xy 18.706592 -116.891054) (xy 18.706592 -117.399054) (xy 18.325592 -117.399054) (xy 18.325592 -116.891054)
				)
			)
		)
		(zone
			(layer "F.Cu")
			(hatch none 0.5)
			(connect_pads
				(clearance 0)
			)
			(min_thickness 0.25)
			(keepout
				(tracks not_allowed)
				(vias allowed)
				(pads allowed)
				(copperpour not_allowed)
				(footprints allowed)
			)
			(placement
				(enabled no)
				(sheetname "")
			)
			(fill
				(thermal_gap 0.5)
				(thermal_bridge_width 0.5)
				(island_removal_mode 0)
			)
			(polygon
				(pts
					(xy 18.706592 -116.891054) (xy 18.706592 -117.399054) (xy 18.325592 -117.399054) (xy 18.325592 -116.891054)
				)
			)
		)
	)
	(footprint ""
		(layer "F.Cu")
		(at 384.422904 -76.915264)
		(property "Reference" "R2T43"
			(at 0 0 0)
			(layer "F.SilkS")
			(hide yes)
			(effects
				(font
					(size 1.27 1.27)
				)
			)
		)
		(property "Value" ""
			(at 0 0 0)
			(layer "F.Fab")
			(effects
				(font
					(size 1.27 1.27)
				)
			)
		)
		(duplicate_pad_numbers_are_jumpers no)
		(fp_poly
			(pts
				(xy -0.2794 -0.1016) (xy 0.2794 -0.1016) (xy 0.2794 0.9906) (xy -0.2794 0.9906)
			)
			(stroke
				(width 0)
				(type default)
			)
			(fill no)
			(layer "F.CrtYd")
		)
		(fp_line
			(start -0.2794 -0.1016)
			(end -0.2794 0.9906)
			(stroke
				(width 0.1)
				(type default)
			)
			(layer "F.Fab")
		)
		(fp_line
			(start -0.2794 0.9906)
			(end 0.2794 0.9906)
			(stroke
				(width 0.1)
				(type default)
			)
			(layer "F.Fab")
		)
		(fp_line
			(start 0.2794 -0.1016)
			(end -0.2794 -0.1016)
			(stroke
				(width 0.1)
				(type default)
			)
			(layer "F.Fab")
		)
		(fp_line
			(start 0.2794 0.9906)
			(end 0.2794 -0.1016)
			(stroke
				(width 0.1)
				(type default)
			)
			(layer "F.Fab")
		)
		(pad "1" smd rect
			(at 0 0)
			(size 0.508 0.508)
			(layers "F.Cu" "F.Mask" "F.Paste")
			(net "H_CPU_ERR2_G_R_N")
		)
		(pad "2" smd rect
			(at 0 0.889)
			(size 0.508 0.508)
			(layers "F.Cu" "F.Mask" "F.Paste")
			(net "H_CPU_ERR2_GTL_N")
		)
		(zone
			(layer "F.Cu")
			(hatch none 0.5)
			(connect_pads
				(clearance 0)
			)
			(min_thickness 0.25)
			(keepout
				(tracks allowed)
				(vias not_allowed)
				(pads allowed)
				(copperpour not_allowed)
				(footprints allowed)
			)
			(placement
				(enabled no)
				(sheetname "")
			)
			(fill
				(thermal_gap 0.5)
				(thermal_bridge_width 0.5)
				(island_removal_mode 0)
			)
			(polygon
				(pts
					(xy 384.168904 -76.661264) (xy 384.676904 -76.661264) (xy 384.676904 -76.280264) (xy 384.168904 -76.280264)
				)
			)
		)
		(zone
			(layer "F.Cu")
			(hatch none 0.5)
			(connect_pads
				(clearance 0)
			)
			(min_thickness 0.25)
			(keepout
				(tracks not_allowed)
				(vias allowed)
				(pads allowed)
				(copperpour not_allowed)
				(footprints allowed)
			)
			(placement
				(enabled no)
				(sheetname "")
			)
			(fill
				(thermal_gap 0.5)
				(thermal_bridge_width 0.5)
				(island_removal_mode 0)
			)
			(polygon
				(pts
					(xy 384.168904 -76.280264) (xy 384.676904 -76.280264) (xy 384.676904 -76.661264) (xy 384.168904 -76.661264)
				)
			)
		)
	)
	(footprint ""
		(layer "F.Cu")
		(at 264.431272 -77.636116)
		(property "Reference" "C5D29"
			(at 0 0 0)
			(layer "F.SilkS")
			(hide yes)
			(effects
				(font
					(size 1.27 1.27)
				)
			)
		)
		(property "Value" ""
			(at 0 0 0)
			(layer "F.Fab")
			(effects
				(font
					(size 1.27 1.27)
				)
			)
		)
		(duplicate_pad_numbers_are_jumpers no)
		(fp_poly
			(pts
				(xy -0.4953 -0.2032) (xy 0.4953 -0.2032) (xy 0.4953 1.6002) (xy -0.4953 1.6002)
			)
			(stroke
				(width 0)
				(type default)
			)
			(fill no)
			(layer "F.CrtYd")
		)
		(fp_line
			(start -0.4953 -0.2032)
			(end 0.4953 -0.2032)
			(stroke
				(width 0.1)
				(type default)
			)
			(layer "F.Fab")
		)
		(fp_line
			(start -0.4953 1.6002)
			(end -0.4953 -0.2032)
			(stroke
				(width 0.1)
				(type default)
			)
			(layer "F.Fab")
		)
		(fp_line
			(start 0.4953 -0.2032)
			(end 0.4953 1.6002)
			(stroke
				(width 0.1)
				(type default)
			)
			(layer "F.Fab")
		)
		(fp_line
			(start 0.4953 1.6002)
			(end -0.4953 1.6002)
			(stroke
				(width 0.1)
				(type default)
			)
			(layer "F.Fab")
		)
		(pad "1" smd rect
			(at 0 0)
			(size 0.762 0.889)
			(layers "F.Cu" "F.Mask" "F.Paste")
			(net "PVCCIN_CPU0")
		)
		(pad "2" smd rect
			(at 0 1.397)
			(size 0.762 0.889)
			(layers "F.Cu" "F.Mask" "F.Paste")
			(net "GND")
		)
		(zone
			(layer "F.Cu")
			(hatch none 0.5)
			(connect_pads
				(clearance 0)
			)
			(min_thickness 0.25)
			(keepout
				(tracks not_allowed)
				(vias allowed)
				(pads allowed)
				(copperpour not_allowed)
				(footprints allowed)
			)
			(placement
				(enabled no)
				(sheetname "")
			)
			(fill
				(thermal_gap 0.5)
				(thermal_bridge_width 0.5)
				(island_removal_mode 0)
			)
			(polygon
				(pts
					(xy 264.050272 -77.191616) (xy 264.812272 -77.191616) (xy 264.812272 -76.683616) (xy 264.050272 -76.683616)
				)
			)
		)
	)
	(footprint ""
		(layer "F.Cu")
		(at 368.554 -112.395 90)
		(property "Reference" "C7B29"
			(at 0 0 90)
			(layer "F.SilkS")
			(hide yes)
			(effects
				(font
					(size 1.27 1.27)
				)
			)
		)
		(property "Value" ""
			(at 0 0 90)
			(layer "F.Fab")
			(effects
				(font
					(size 1.27 1.27)
				)
			)
		)
		(duplicate_pad_numbers_are_jumpers no)
		(fp_poly
			(pts
				(xy 0.3048 -0.1016) (xy 0.3048 0.9906) (xy -0.3048 0.9906) (xy -0.3048 -0.1016)
			)
			(stroke
				(width 0)
				(type default)
			)
			(fill no)
			(layer "F.CrtYd")
		)
		(fp_line
			(start 0.3048 -0.1016)
			(end -0.3048 -0.1016)
			(stroke
				(width 0.1)
				(type default)
			)
			(layer "F.Fab")
		)
		(fp_line
			(start -0.3048 -0.1016)
			(end -0.3048 0.9906)
			(stroke
				(width 0.1)
				(type default)
			)
			(layer "F.Fab")
		)
		(fp_line
			(start 0.3048 0.9906)
			(end 0.3048 -0.1016)
			(stroke
				(width 0.1)
				(type default)
			)
			(layer "F.Fab")
		)
		(fp_line
			(start -0.3048 0.9906)
			(end 0.3048 0.9906)
			(stroke
				(width 0.1)
				(type default)
			)
			(layer "F.Fab")
		)
		(pad "1" smd rect
			(at 0 0 90)
			(size 0.508 0.508)
			(layers "F.Cu" "F.Mask" "F.Paste")
			(net "DMI_CPU0_PCH_TX_DN<2>")
		)
		(pad "2" smd rect
			(at 0 0.889 90)
			(size 0.508 0.508)
			(layers "F.Cu" "F.Mask" "F.Paste")
			(net "DMI_CPU0_PCH_TX_C_DN<2>")
		)
		(zone
			(layer "F.Cu")
			(hatch none 0.5)
			(connect_pads
				(clearance 0)
			)
			(min_thickness 0.25)
			(keepout
				(tracks allowed)
				(vias not_allowed)
				(pads allowed)
				(copperpour not_allowed)
				(footprints allowed)
			)
			(placement
				(enabled no)
				(sheetname "")
			)
			(fill
				(thermal_gap 0.5)
				(thermal_bridge_width 0.5)
				(island_removal_mode 0)
			)
			(polygon
				(pts
					(xy 368.808 -112.141) (xy 368.808 -112.649) (xy 369.189 -112.649) (xy 369.189 -112.141)
				)
			)
		)
		(zone
			(layer "F.Cu")
			(hatch none 0.5)
			(connect_pads
				(clearance 0)
			)
			(min_thickness 0.25)
			(keepout
				(tracks not_allowed)
				(vias allowed)
				(pads allowed)
				(copperpour not_allowed)
				(footprints allowed)
			)
			(placement
				(enabled no)
				(sheetname "")
			)
			(fill
				(thermal_gap 0.5)
				(thermal_bridge_width 0.5)
				(island_removal_mode 0)
			)
			(polygon
				(pts
					(xy 369.189 -112.141) (xy 369.189 -112.649) (xy 368.808 -112.649) (xy 368.808 -112.141)
				)
			)
		)
	)
	(footprint ""
		(layer "F.Cu")
		(at 14.605 -97.028 180)
		(property "Reference" "C1C14"
			(at 0 0 180)
			(layer "F.SilkS")
			(hide yes)
			(effects
				(font
					(size 1.27 1.27)
				)
			)
		)
		(property "Value" ""
			(at 0 0 180)
			(layer "F.Fab")
			(effects
				(font
					(size 1.27 1.27)
				)
			)
		)
		(duplicate_pad_numbers_are_jumpers no)
		(fp_rect
			(start 0.3048 -0.1016)
			(end -0.3048 0.9906)
			(stroke
				(width 0)
				(type default)
			)
			(fill no)
			(layer "F.CrtYd")
		)
		(fp_line
			(start 0.3048 0.9906)
			(end 0.3048 -0.1016)
			(stroke
				(width 0.1)
				(type default)
			)
			(layer "F.Fab")
		)
		(fp_line
			(start 0.3048 -0.1016)
			(end -0.3048 -0.1016)
			(stroke
				(width 0.1)
				(type default)
			)
			(layer "F.Fab")
		)
		(fp_line
			(start -0.3048 0.9906)
			(end 0.3048 0.9906)
			(stroke
				(width 0.1)
				(type default)
			)
			(layer "F.Fab")
		)
		(fp_line
			(start -0.3048 -0.1016)
			(end -0.3048 0.9906)
			(stroke
				(width 0.1)
				(type default)
			)
			(layer "F.Fab")
		)
		(pad "1" smd rect
			(at 0 0 180)
			(size 0.508 0.508)
			(layers "F.Cu" "F.Mask" "F.Paste")
			(net "VR_PVCCIN_CPU1_VD12")
		)
		(pad "2" smd rect
			(at 0 0.889 180)
			(size 0.508 0.508)
			(layers "F.Cu" "F.Mask" "F.Paste")
			(net "GND")
		)
		(zone
			(layer "F.Cu")
			(hatch none 0.5)
			(connect_pads
				(clearance 0)
			)
			(min_thickness 0.25)
			(keepout
				(tracks allowed)
				(vias not_allowed)
				(pads allowed)
				(copperpour not_allowed)
				(footprints allowed)
			)
			(placement
				(enabled no)
				(sheetname "")
			)
			(fill
				(thermal_gap 0.5)
				(thermal_bridge_width 0.5)
				(island_removal_mode 0)
			)
			(polygon
				(pts
					(xy 14.351 -97.282) (xy 14.859 -97.282) (xy 14.859 -97.663) (xy 14.351 -97.663)
				)
			)
		)
		(zone
			(layer "F.Cu")
			(hatch none 0.5)
			(connect_pads
				(clearance 0)
			)
			(min_thickness 0.25)
			(keepout
				(tracks not_allowed)
				(vias allowed)
				(pads allowed)
				(copperpour not_allowed)
				(footprints allowed)
			)
			(placement
				(enabled no)
				(sheetname "")
			)
			(fill
				(thermal_gap 0.5)
				(thermal_bridge_width 0.5)
				(island_removal_mode 0)
			)
			(polygon
				(pts
					(xy 14.351 -97.282) (xy 14.859 -97.282) (xy 14.859 -97.663) (xy 14.351 -97.663)
				)
			)
		)
	)
	(footprint ""
		(layer "F.Cu")
		(at 202.184 -26.162)
		(property "Reference" ""
			(at 0 0 0)
			(layer "F.SilkS")
			(hide yes)
			(effects
				(font
					(size 1.27 1.27)
				)
			)
		)
		(property "Value" ""
			(at 0 0 0)
			(layer "F.Fab")
			(effects
				(font
					(size 1.27 1.27)
				)
			)
		)
		(duplicate_pad_numbers_are_jumpers no)
		(fp_poly
			(pts
				(arc
					(start 2.032 0)
					(mid -2.032 0)
					(end 2.032 0)
				)
			)
			(stroke
				(width 0)
				(type default)
			)
			(fill no)
			(layer "F.CrtYd")
		)
		(pad "1" smd circle
			(at 0 0)
			(size 1.016 1.016)
			(layers "F.Cu" "F.Mask" "F.Paste")
			(net "Net_391")
		)
		(zone
			(layer "F.Cu")
			(hatch none 0.5)
			(connect_pads
				(clearance 0)
			)
			(min_thickness 0.25)
			(keepout
				(tracks not_allowed)
				(vias allowed)
				(pads allowed)
				(copperpour not_allowed)
				(footprints allowed)
			)
			(placement
				(enabled no)
				(sheetname "")
			)
			(fill
				(thermal_gap 0.5)
				(thermal_bridge_width 0.5)
				(island_removal_mode 0)
			)
			(polygon
				(pts
					(arc
						(start 203.708 -26.162)
						(mid 200.66 -26.162)
						(end 203.708 -26.162)
					)
				)
			)
		)
		(zone
			(layers "F.Cu" "B.Cu" "In1.Cu" "In2.Cu" "In3.Cu" "In4.Cu" "In5.Cu" "In6.Cu"
				"In7.Cu" "In8.Cu" "In9.Cu" "In10.Cu" "In11.Cu" "In12.Cu"
			)
			(hatch none 0.5)
			(connect_pads
				(clearance 0)
			)
			(min_thickness 0.25)
			(keepout
				(tracks allowed)
				(vias not_allowed)
				(pads allowed)
				(copperpour not_allowed)
				(footprints allowed)
			)
			(placement
				(enabled no)
				(sheetname "")
			)
			(fill
				(thermal_gap 0.5)
				(thermal_bridge_width 0.5)
				(island_removal_mode 0)
			)
			(polygon
				(pts
					(arc
						(start 203.708 -26.162)
						(mid 200.66 -26.162)
						(end 203.708 -26.162)
					)
				)
			)
		)
	)
)
